FILE_TYPE = CONNECTIVITY;
{Allegro Design Entry HDL 17.2-2016 S081 (4005846) 1/11/2022}
"PAGE_NUMBER" = 65;
0"NC";
1"UPI_CPU1_CPU0_P2P2_DP<23:0>";
2"UPI_CPU1_CPU0_P2P2_DN<23:0>";
3"UPI_CPU0_CPU1_P2P2_DP<23:0>";
4"UPI_CPU0_CPU1_P2P2_DN<23:0>";
5"UPI_CPU0_CPU1_P2P2_DN<23>";
6"UPI_CPU0_CPU1_P2P2_DN<22>";
7"UPI_CPU0_CPU1_P2P2_DN<21>";
8"UPI_CPU0_CPU1_P2P2_DN<20>";
9"UPI_CPU0_CPU1_P2P2_DN<19>";
10"UPI_CPU0_CPU1_P2P2_DN<18>";
11"UPI_CPU0_CPU1_P2P2_DN<17>";
12"UPI_CPU0_CPU1_P2P2_DN<16>";
13"UPI_CPU0_CPU1_P2P2_DN<15>";
14"UPI_CPU0_CPU1_P2P2_DN<14>";
15"UPI_CPU0_CPU1_P2P2_DN<13>";
16"UPI_CPU0_CPU1_P2P2_DN<12>";
17"UPI_CPU0_CPU1_P2P2_DN<11>";
18"UPI_CPU0_CPU1_P2P2_DN<10>";
19"UPI_CPU0_CPU1_P2P2_DN<9>";
20"UPI_CPU0_CPU1_P2P2_DN<8>";
21"UPI_CPU0_CPU1_P2P2_DN<7>";
22"UPI_CPU0_CPU1_P2P2_DN<6>";
23"UPI_CPU0_CPU1_P2P2_DN<5>";
24"UPI_CPU0_CPU1_P2P2_DN<4>";
25"UPI_CPU0_CPU1_P2P2_DN<3>";
26"UPI_CPU0_CPU1_P2P2_DN<2>";
27"UPI_CPU0_CPU1_P2P2_DN<1>";
28"UPI_CPU0_CPU1_P2P2_DN<0>";
29"UPI_CPU0_CPU1_P2P2_DP<23>";
30"UPI_CPU0_CPU1_P2P2_DP<22>";
31"UPI_CPU0_CPU1_P2P2_DP<21>";
32"UPI_CPU0_CPU1_P2P2_DP<20>";
33"UPI_CPU0_CPU1_P2P2_DP<19>";
34"UPI_CPU0_CPU1_P2P2_DP<18>";
35"UPI_CPU0_CPU1_P2P2_DP<17>";
36"UPI_CPU0_CPU1_P2P2_DP<16>";
37"UPI_CPU0_CPU1_P2P2_DP<15>";
38"UPI_CPU0_CPU1_P2P2_DP<14>";
39"UPI_CPU0_CPU1_P2P2_DP<13>";
40"UPI_CPU0_CPU1_P2P2_DP<12>";
41"UPI_CPU0_CPU1_P2P2_DP<11>";
42"UPI_CPU0_CPU1_P2P2_DP<10>";
43"UPI_CPU0_CPU1_P2P2_DP<9>";
44"UPI_CPU0_CPU1_P2P2_DP<8>";
45"UPI_CPU0_CPU1_P2P2_DP<7>";
46"UPI_CPU0_CPU1_P2P2_DP<6>";
47"UPI_CPU0_CPU1_P2P2_DP<5>";
48"UPI_CPU0_CPU1_P2P2_DP<4>";
49"UPI_CPU0_CPU1_P2P2_DP<3>";
50"UPI_CPU0_CPU1_P2P2_DP<2>";
51"UPI_CPU0_CPU1_P2P2_DP<1>";
52"UPI_CPU0_CPU1_P2P2_DP<0>";
53"UPI_CPU1_CPU0_P2P2_DN<23>";
54"UPI_CPU1_CPU0_P2P2_DN<22>";
55"UPI_CPU1_CPU0_P2P2_DN<21>";
56"UPI_CPU1_CPU0_P2P2_DN<20>";
57"UPI_CPU1_CPU0_P2P2_DN<19>";
58"UPI_CPU1_CPU0_P2P2_DN<18>";
59"UPI_CPU1_CPU0_P2P2_DN<17>";
60"UPI_CPU1_CPU0_P2P2_DN<16>";
61"UPI_CPU1_CPU0_P2P2_DN<15>";
62"UPI_CPU1_CPU0_P2P2_DN<14>";
63"UPI_CPU1_CPU0_P2P2_DN<13>";
64"UPI_CPU1_CPU0_P2P2_DN<12>";
65"UPI_CPU1_CPU0_P2P2_DN<11>";
66"UPI_CPU1_CPU0_P2P2_DN<10>";
67"UPI_CPU1_CPU0_P2P2_DN<9>";
68"UPI_CPU1_CPU0_P2P2_DN<8>";
69"UPI_CPU1_CPU0_P2P2_DN<7>";
70"UPI_CPU1_CPU0_P2P2_DN<6>";
71"UPI_CPU1_CPU0_P2P2_DN<5>";
72"UPI_CPU1_CPU0_P2P2_DN<4>";
73"UPI_CPU1_CPU0_P2P2_DN<3>";
74"UPI_CPU1_CPU0_P2P2_DN<2>";
75"UPI_CPU1_CPU0_P2P2_DN<1>";
76"UPI_CPU1_CPU0_P2P2_DN<0>";
77"UPI_CPU1_CPU0_P2P2_DP<23>";
78"UPI_CPU1_CPU0_P2P2_DP<22>";
79"UPI_CPU1_CPU0_P2P2_DP<21>";
80"UPI_CPU1_CPU0_P2P2_DP<20>";
81"UPI_CPU1_CPU0_P2P2_DP<19>";
82"UPI_CPU1_CPU0_P2P2_DP<18>";
83"UPI_CPU1_CPU0_P2P2_DP<17>";
84"UPI_CPU1_CPU0_P2P2_DP<16>";
85"UPI_CPU1_CPU0_P2P2_DP<15>";
86"UPI_CPU1_CPU0_P2P2_DP<14>";
87"UPI_CPU1_CPU0_P2P2_DP<13>";
88"UPI_CPU1_CPU0_P2P2_DP<12>";
89"UPI_CPU1_CPU0_P2P2_DP<11>";
90"UPI_CPU1_CPU0_P2P2_DP<10>";
91"UPI_CPU1_CPU0_P2P2_DP<9>";
92"UPI_CPU1_CPU0_P2P2_DP<8>";
93"UPI_CPU1_CPU0_P2P2_DP<7>";
94"UPI_CPU1_CPU0_P2P2_DP<6>";
95"UPI_CPU1_CPU0_P2P2_DP<5>";
96"UPI_CPU1_CPU0_P2P2_DP<4>";
97"UPI_CPU1_CPU0_P2P2_DP<3>";
98"UPI_CPU1_CPU0_P2P2_DP<2>";
99"UPI_CPU1_CPU0_P2P2_DP<1>";
100"UPI_CPU1_CPU0_P2P2_DP<0>";
%"TAP"
"1","(-75,1875)","2","standard","I10";
;
CDS_LIB"standard"
BODY_TYPE"PLUMBING"
HDL_TAP"TRUE";
"B \NAC \NWC"4;
"S \NAC"
BN"6"22;
%"TAP"
"1","(-75,1975)","2","standard","I11";
;
CDS_LIB"standard"
BODY_TYPE"PLUMBING"
HDL_TAP"TRUE";
"B \NAC \NWC"4;
"S \NAC"
BN"8"20;
%"TAP"
"1","(-75,2025)","2","standard","I12";
;
CDS_LIB"standard"
BODY_TYPE"PLUMBING"
HDL_TAP"TRUE";
"B \NAC \NWC"4;
"S \NAC"
BN"9"19;
%"TAP"
"1","(-75,2075)","2","standard","I13";
;
CDS_LIB"standard"
BODY_TYPE"PLUMBING"
HDL_TAP"TRUE";
"B \NAC \NWC"4;
"S \NAC"
BN"10"18;
%"TAP"
"1","(-75,2125)","2","standard","I14";
;
CDS_LIB"standard"
BODY_TYPE"PLUMBING"
HDL_TAP"TRUE";
"B \NAC \NWC"4;
"S \NAC"
BN"11"17;
%"TAP"
"1","(-75,2175)","2","standard","I15";
;
CDS_LIB"standard"
BODY_TYPE"PLUMBING"
HDL_TAP"TRUE";
"B \NAC \NWC"4;
"S \NAC"
BN"12"16;
%"SOCKET4677_AZIF0045P001C01CS"
"24","(1625,2775)","0","pure_quanta","I16";
;
PART_NUMBER"DGA^7000023"
VALUE"SOCKET4677_AZIF0045-P001C01CS"
MATERIAL"IO"
PART_TYPE"SMLF"
$LOCATION"U1"
CDS_LMAN_SYM_OUTLINE"-1050,1350,1050,-1350"
NEEDS_NO_SIZE"TRUE"
CDS_LIB"pure_quanta"
CDS_LOCATION"U1"
$SEC"24"
CDS_SEC"24";
"UPI2_TX_DP0"
$PN"D85"100;
"UPI2_TX_DP1"
$PN"F85"99;
"UPI2_TX_DP2"
$PN"E88"98;
"UPI2_TX_DP3"
$PN"H87"97;
"UPI2_TX_DP4"
$PN"G86"96;
"UPI2_TX_DP5"
$PN"T81"95;
"UPI2_TX_DP6"
$PN"P83"94;
"UPI2_TX_DP7"
$PN"V81"93;
"UPI2_TX_DP8"
$PN"Y83"92;
"UPI2_TX_DP9"
$PN"W82"91;
"UPI2_TX_DP10"
$PN"BA78"90;
"UPI2_TX_DP11"
$PN"AV79"89;
"UPI2_TX_DP12"
$PN"AP81"88;
"UPI2_TX_DP13"
$PN"AM83"87;
"UPI2_TX_DP14"
$PN"AT81"86;
"UPI2_TX_DP15"
$PN"AV83"85;
"UPI2_TX_DP16"
$PN"AU82"84;
"UPI2_TX_DP17"
$PN"BB81"83;
"UPI2_TX_DP18"
$PN"BA82"82;
"UPI2_TX_DP19"
$PN"BD83"81;
"UPI2_TX_DP20"
$PN"BC80"80;
"UPI2_TX_DP21"
$PN"BG82"79;
"UPI2_TX_DP22"
$PN"BE80"78;
"UPI2_TX_DP23"
$PN"BN72"77;
"UPI2_TX_DN0"
$PN"B85"76;
"UPI2_TX_DN1"
$PN"E84"75;
"UPI2_TX_DN2"
$PN"D87"74;
"UPI2_TX_DN3"
$PN"F87"73;
"UPI2_TX_DN4"
$PN"H85"72;
"UPI2_TX_DN5"
$PN"P81"71;
"UPI2_TX_DN6"
$PN"R82"70;
"UPI2_TX_DN7"
$PN"U80"69;
"UPI2_TX_DN8"
$PN"V83"68;
"UPI2_TX_DN9"
$PN"Y81"67;
"UPI2_TX_DN10"
$PN"AW78"66;
"UPI2_TX_DN11"
$PN"AU78"65;
"UPI2_TX_DN12"
$PN"AM81"64;
"UPI2_TX_DN13"
$PN"AN82"63;
"UPI2_TX_DN14"
$PN"AR80"62;
"UPI2_TX_DN15"
$PN"AT83"61;
"UPI2_TX_DN16"
$PN"AV81"60;
"UPI2_TX_DN17"
$PN"BA80"59;
"UPI2_TX_DN18"
$PN"BC82"58;
"UPI2_TX_DN19"
$PN"BE82"57;
"UPI2_TX_DN20"
$PN"BD79"56;
"UPI2_TX_DN21"
$PN"BF81"55;
"UPI2_TX_DN22"
$PN"BG80"54;
"UPI2_TX_DN23"
$PN"BM71"53;
"UPI2_RX_DP0"
$PN"G80"52;
"UPI2_RX_DP1"
$PN"E82"51;
"UPI2_RX_DP2"
$PN"H83"50;
"UPI2_RX_DP3"
$PN"M79"49;
"UPI2_RX_DP4"
$PN"L82"48;
"UPI2_RX_DP5"
$PN"K81"47;
"UPI2_RX_DP6"
$PN"AE80"46;
"UPI2_RX_DP7"
$PN"AC82"45;
"UPI2_RX_DP8"
$PN"AG80"44;
"UPI2_RX_DP9"
$PN"AF83"43;
"UPI2_RX_DP10"
$PN"AH81"42;
"UPI2_RX_DP11"
$PN"AJ82"41;
"UPI2_RX_DP12"
$PN"BB73"40;
"UPI2_RX_DP13"
$PN"AY73"39;
"UPI2_RX_DP14"
$PN"BA76"38;
"UPI2_RX_DP15"
$PN"BD75"37;
"UPI2_RX_DP16"
$PN"AV75"36;
"UPI2_RX_DP17"
$PN"BG76"35;
"UPI2_RX_DP18"
$PN"BK77"34;
"UPI2_RX_DP19"
$PN"BN76"33;
"UPI2_RX_DP20"
$PN"BJ74"32;
"UPI2_RX_DP21"
$PN"BM75"31;
"UPI2_RX_DP22"
$PN"BL74"30;
"UPI2_RX_DP23"
$PN"BC74"29;
"UPI2_RX_DN0"
$PN"E80"28;
"UPI2_RX_DN1"
$PN"F81"27;
"UPI2_RX_DN2"
$PN"G82"26;
"UPI2_RX_DN3"
$PN"K79"25;
"UPI2_RX_DN4"
$PN"J82"24;
"UPI2_RX_DN5"
$PN"L80"23;
"UPI2_RX_DN6"
$PN"AC80"22;
"UPI2_RX_DN7"
$PN"AD81"21;
"UPI2_RX_DN8"
$PN"AF79"20;
"UPI2_RX_DN9"
$PN"AE82"19;
"UPI2_RX_DN10"
$PN"AJ80"18;
"UPI2_RX_DN11"
$PN"AG82"17;
"UPI2_RX_DN12"
$PN"BA72"16;
"UPI2_RX_DN13"
$PN"AV73"15;
"UPI2_RX_DN14"
$PN"AY75"14;
"UPI2_RX_DN15"
$PN"BB75"13;
"UPI2_RX_DN16"
$PN"AW74"12;
"UPI2_RX_DN17"
$PN"BH75"11;
"UPI2_RX_DN18"
$PN"BJ76"10;
"UPI2_RX_DN19"
$PN"BL76"9;
"UPI2_RX_DN20"
$PN"BG74"8;
"UPI2_RX_DN21"
$PN"BN74"7;
"UPI2_RX_DN22"
$PN"BK73"6;
"UPI2_RX_DN23"
$PN"BD73"5;
%"TAP"
"1","(-75,2225)","2","standard","I17";
;
CDS_LIB"standard"
BODY_TYPE"PLUMBING"
HDL_TAP"TRUE";
"B \NAC \NWC"4;
"S \NAC"
BN"13"15;
%"TAP"
"1","(-75,2275)","2","standard","I18";
;
CDS_LIB"standard"
BODY_TYPE"PLUMBING"
HDL_TAP"TRUE";
"B \NAC \NWC"4;
"S \NAC"
BN"14"14;
%"TAP"
"1","(-75,2325)","2","standard","I19";
;
CDS_LIB"standard"
BODY_TYPE"PLUMBING"
HDL_TAP"TRUE";
"B \NAC \NWC"4;
"S \NAC"
BN"15"13;
%"TAP"
"1","(-75,2375)","2","standard","I20";
;
CDS_LIB"standard"
BODY_TYPE"PLUMBING"
HDL_TAP"TRUE";
"B \NAC \NWC"4;
"S \NAC"
BN"16"12;
%"TAP"
"1","(-75,2425)","2","standard","I21";
;
CDS_LIB"standard"
BODY_TYPE"PLUMBING"
HDL_TAP"TRUE";
"B \NAC \NWC"4;
"S \NAC"
BN"17"11;
%"TAP"
"1","(-75,2475)","2","standard","I22";
;
CDS_LIB"standard"
BODY_TYPE"PLUMBING"
HDL_TAP"TRUE";
"B \NAC \NWC"4;
"S \NAC"
BN"18"10;
%"TAP"
"1","(-75,2525)","2","standard","I23";
;
CDS_LIB"standard"
BODY_TYPE"PLUMBING"
HDL_TAP"TRUE";
"B \NAC \NWC"4;
"S \NAC"
BN"19"9;
%"TAP"
"1","(-75,2575)","2","standard","I24";
;
CDS_LIB"standard"
BODY_TYPE"PLUMBING"
HDL_TAP"TRUE";
"B \NAC \NWC"4;
"S \NAC"
BN"20"8;
%"TAP"
"1","(-75,2675)","2","standard","I25";
;
CDS_LIB"standard"
BODY_TYPE"PLUMBING"
HDL_TAP"TRUE";
"B \NAC \NWC"4;
"S \NAC"
BN"22"6;
%"TAP"
"1","(-75,2625)","2","standard","I26";
;
CDS_LIB"standard"
BODY_TYPE"PLUMBING"
HDL_TAP"TRUE";
"B \NAC \NWC"4;
"S \NAC"
BN"21"7;
%"TAP"
"1","(-75,2725)","2","standard","I27";
;
CDS_LIB"standard"
BODY_TYPE"PLUMBING"
HDL_TAP"TRUE";
"B \NAC \NWC"4;
"S \NAC"
BN"23"5;
%"TAP"
"1","(-75,2825)","2","standard","I28";
;
CDS_LIB"standard"
BODY_TYPE"PLUMBING"
HDL_TAP"TRUE";
"B \NAC \NWC"3;
"S \NAC"
BN"0"52;
%"TAP"
"1","(-75,2875)","2","standard","I29";
;
CDS_LIB"standard"
BODY_TYPE"PLUMBING"
HDL_TAP"TRUE";
"B \NAC \NWC"3;
"S \NAC"
BN"1"51;
%"TAP"
"1","(-75,1575)","2","standard","I3";
;
CDS_LIB"standard"
BODY_TYPE"PLUMBING"
HDL_TAP"TRUE";
"B \NAC \NWC"4;
"S \NAC"
BN"0"28;
%"TAP"
"1","(-75,2925)","2","standard","I30";
;
CDS_LIB"standard"
BODY_TYPE"PLUMBING"
HDL_TAP"TRUE";
"B \NAC \NWC"3;
"S \NAC"
BN"2"50;
%"TAP"
"1","(-75,2975)","2","standard","I31";
;
CDS_LIB"standard"
BODY_TYPE"PLUMBING"
HDL_TAP"TRUE";
"B \NAC \NWC"3;
"S \NAC"
BN"3"49;
%"TAP"
"1","(-75,3025)","2","standard","I32";
;
CDS_LIB"standard"
BODY_TYPE"PLUMBING"
HDL_TAP"TRUE";
"B \NAC \NWC"3;
"S \NAC"
BN"4"48;
%"TAP"
"1","(-75,3075)","2","standard","I33";
;
CDS_LIB"standard"
BODY_TYPE"PLUMBING"
HDL_TAP"TRUE";
"B \NAC \NWC"3;
"S \NAC"
BN"5"47;
%"TAP"
"1","(-75,3175)","2","standard","I34";
;
CDS_LIB"standard"
BODY_TYPE"PLUMBING"
HDL_TAP"TRUE";
"B \NAC \NWC"3;
"S \NAC"
BN"7"45;
%"TAP"
"1","(-75,3125)","2","standard","I35";
;
CDS_LIB"standard"
BODY_TYPE"PLUMBING"
HDL_TAP"TRUE";
"B \NAC \NWC"3;
"S \NAC"
BN"6"46;
%"TAP"
"1","(-75,3225)","2","standard","I36";
;
CDS_LIB"standard"
BODY_TYPE"PLUMBING"
HDL_TAP"TRUE";
"B \NAC \NWC"3;
"S \NAC"
BN"8"44;
%"TAP"
"1","(-75,3275)","2","standard","I37";
;
CDS_LIB"standard"
BODY_TYPE"PLUMBING"
HDL_TAP"TRUE";
"B \NAC \NWC"3;
"S \NAC"
BN"9"43;
%"TAP"
"1","(-75,3325)","2","standard","I38";
;
CDS_LIB"standard"
BODY_TYPE"PLUMBING"
HDL_TAP"TRUE";
"B \NAC \NWC"3;
"S \NAC"
BN"10"42;
%"TAP"
"1","(-75,3375)","2","standard","I39";
;
CDS_LIB"standard"
BODY_TYPE"PLUMBING"
HDL_TAP"TRUE";
"B \NAC \NWC"3;
"S \NAC"
BN"11"41;
%"TAP"
"1","(-75,1675)","2","standard","I4";
;
CDS_LIB"standard"
BODY_TYPE"PLUMBING"
HDL_TAP"TRUE";
"B \NAC \NWC"4;
"S \NAC"
BN"2"26;
%"TAP"
"1","(-75,3425)","2","standard","I40";
;
CDS_LIB"standard"
BODY_TYPE"PLUMBING"
HDL_TAP"TRUE";
"B \NAC \NWC"3;
"S \NAC"
BN"12"40;
%"TAP"
"1","(-75,3475)","2","standard","I41";
;
CDS_LIB"standard"
BODY_TYPE"PLUMBING"
HDL_TAP"TRUE";
"B \NAC \NWC"3;
"S \NAC"
BN"13"39;
%"TAP"
"1","(-75,3525)","2","standard","I42";
;
CDS_LIB"standard"
BODY_TYPE"PLUMBING"
HDL_TAP"TRUE";
"B \NAC \NWC"3;
"S \NAC"
BN"14"38;
%"TAP"
"1","(-75,3575)","2","standard","I43";
;
CDS_LIB"standard"
BODY_TYPE"PLUMBING"
HDL_TAP"TRUE";
"B \NAC \NWC"3;
"S \NAC"
BN"15"37;
%"TAP"
"1","(-75,3625)","2","standard","I44";
;
CDS_LIB"standard"
BODY_TYPE"PLUMBING"
HDL_TAP"TRUE";
"B \NAC \NWC"3;
"S \NAC"
BN"16"36;
%"TAP"
"1","(-75,3675)","2","standard","I45";
;
CDS_LIB"standard"
BODY_TYPE"PLUMBING"
HDL_TAP"TRUE";
"B \NAC \NWC"3;
"S \NAC"
BN"17"35;
%"TAP"
"1","(-75,3725)","2","standard","I46";
;
CDS_LIB"standard"
BODY_TYPE"PLUMBING"
HDL_TAP"TRUE";
"B \NAC \NWC"3;
"S \NAC"
BN"18"34;
%"TAP"
"1","(-75,3775)","2","standard","I47";
;
CDS_LIB"standard"
BODY_TYPE"PLUMBING"
HDL_TAP"TRUE";
"B \NAC \NWC"3;
"S \NAC"
BN"19"33;
%"TAP"
"1","(-75,3825)","2","standard","I48";
;
CDS_LIB"standard"
BODY_TYPE"PLUMBING"
HDL_TAP"TRUE";
"B \NAC \NWC"3;
"S \NAC"
BN"20"32;
%"TAP"
"1","(-75,3875)","2","standard","I49";
;
CDS_LIB"standard"
BODY_TYPE"PLUMBING"
HDL_TAP"TRUE";
"B \NAC \NWC"3;
"S \NAC"
BN"21"31;
%"TAP"
"1","(-75,1625)","2","standard","I5";
;
CDS_LIB"standard"
BODY_TYPE"PLUMBING"
HDL_TAP"TRUE";
"B \NAC \NWC"4;
"S \NAC"
BN"1"27;
%"TAP"
"1","(-75,3925)","2","standard","I50";
;
CDS_LIB"standard"
BODY_TYPE"PLUMBING"
HDL_TAP"TRUE";
"B \NAC \NWC"3;
"S \NAC"
BN"22"30;
%"TAP"
"1","(-75,3975)","2","standard","I51";
;
CDS_LIB"standard"
BODY_TYPE"PLUMBING"
HDL_TAP"TRUE";
"B \NAC \NWC"3;
"S \NAC"
BN"23"29;
%"TAP"
"1","(3300,1675)","0","standard","I52";
;
CDS_LIB"standard"
BODY_TYPE"PLUMBING"
HDL_TAP"TRUE";
"B \NAC \NWC"2;
"S \NAC"
BN"2"74;
%"TAP"
"1","(3300,1625)","0","standard","I53";
;
CDS_LIB"standard"
BODY_TYPE"PLUMBING"
HDL_TAP"TRUE";
"B \NAC \NWC"2;
"S \NAC"
BN"1"75;
%"TAP"
"1","(3300,1575)","0","standard","I54";
;
CDS_LIB"standard"
BODY_TYPE"PLUMBING"
HDL_TAP"TRUE";
"B \NAC \NWC"2;
"S \NAC"
BN"0"76;
%"TAP"
"1","(3300,1775)","0","standard","I55";
;
CDS_LIB"standard"
BODY_TYPE"PLUMBING"
HDL_TAP"TRUE";
"B \NAC \NWC"2;
"S \NAC"
BN"4"72;
%"TAP"
"1","(3300,1825)","0","standard","I56";
;
CDS_LIB"standard"
BODY_TYPE"PLUMBING"
HDL_TAP"TRUE";
"B \NAC \NWC"2;
"S \NAC"
BN"5"71;
%"TAP"
"1","(3300,1725)","0","standard","I57";
;
CDS_LIB"standard"
BODY_TYPE"PLUMBING"
HDL_TAP"TRUE";
"B \NAC \NWC"2;
"S \NAC"
BN"3"73;
%"TAP"
"1","(3300,1925)","0","standard","I58";
;
CDS_LIB"standard"
BODY_TYPE"PLUMBING"
HDL_TAP"TRUE";
"B \NAC \NWC"2;
"S \NAC"
BN"7"69;
%"TAP"
"1","(3300,1875)","0","standard","I59";
;
CDS_LIB"standard"
BODY_TYPE"PLUMBING"
HDL_TAP"TRUE";
"B \NAC \NWC"2;
"S \NAC"
BN"6"70;
%"TAP"
"1","(-75,1725)","2","standard","I6";
;
CDS_LIB"standard"
BODY_TYPE"PLUMBING"
HDL_TAP"TRUE";
"B \NAC \NWC"4;
"S \NAC"
BN"3"25;
%"TAP"
"1","(3300,2075)","0","standard","I60";
;
CDS_LIB"standard"
BODY_TYPE"PLUMBING"
HDL_TAP"TRUE";
"B \NAC \NWC"2;
"S \NAC"
BN"10"66;
%"TAP"
"1","(3300,2025)","0","standard","I61";
;
CDS_LIB"standard"
BODY_TYPE"PLUMBING"
HDL_TAP"TRUE";
"B \NAC \NWC"2;
"S \NAC"
BN"9"67;
%"TAP"
"1","(3300,1975)","0","standard","I62";
;
CDS_LIB"standard"
BODY_TYPE"PLUMBING"
HDL_TAP"TRUE";
"B \NAC \NWC"2;
"S \NAC"
BN"8"68;
%"TAP"
"1","(3300,2175)","0","standard","I63";
;
CDS_LIB"standard"
BODY_TYPE"PLUMBING"
HDL_TAP"TRUE";
"B \NAC \NWC"2;
"S \NAC"
BN"12"64;
%"TAP"
"1","(3300,2125)","0","standard","I64";
;
CDS_LIB"standard"
BODY_TYPE"PLUMBING"
HDL_TAP"TRUE";
"B \NAC \NWC"2;
"S \NAC"
BN"11"65;
%"TAP"
"1","(3300,2225)","0","standard","I65";
;
CDS_LIB"standard"
BODY_TYPE"PLUMBING"
HDL_TAP"TRUE";
"B \NAC \NWC"2;
"S \NAC"
BN"13"63;
%"TAP"
"1","(3300,2325)","0","standard","I66";
;
CDS_LIB"standard"
BODY_TYPE"PLUMBING"
HDL_TAP"TRUE";
"B \NAC \NWC"2;
"S \NAC"
BN"15"61;
%"TAP"
"1","(3300,2275)","0","standard","I67";
;
CDS_LIB"standard"
BODY_TYPE"PLUMBING"
HDL_TAP"TRUE";
"B \NAC \NWC"2;
"S \NAC"
BN"14"62;
%"TAP"
"1","(3300,2425)","0","standard","I68";
;
CDS_LIB"standard"
BODY_TYPE"PLUMBING"
HDL_TAP"TRUE";
"B \NAC \NWC"2;
"S \NAC"
BN"17"59;
%"TAP"
"1","(3300,2375)","0","standard","I69";
;
CDS_LIB"standard"
BODY_TYPE"PLUMBING"
HDL_TAP"TRUE";
"B \NAC \NWC"2;
"S \NAC"
BN"16"60;
%"TAP"
"1","(-75,1775)","2","standard","I7";
;
CDS_LIB"standard"
BODY_TYPE"PLUMBING"
HDL_TAP"TRUE";
"B \NAC \NWC"4;
"S \NAC"
BN"4"24;
%"TAP"
"1","(3300,2475)","0","standard","I70";
;
CDS_LIB"standard"
BODY_TYPE"PLUMBING"
HDL_TAP"TRUE";
"B \NAC \NWC"2;
"S \NAC"
BN"18"58;
%"TAP"
"1","(3300,2725)","0","standard","I71";
;
CDS_LIB"standard"
BODY_TYPE"PLUMBING"
HDL_TAP"TRUE";
"B \NAC \NWC"2;
"S \NAC"
BN"23"53;
%"TAP"
"1","(3300,2675)","0","standard","I72";
;
CDS_LIB"standard"
BODY_TYPE"PLUMBING"
HDL_TAP"TRUE";
"B \NAC \NWC"2;
"S \NAC"
BN"22"54;
%"TAP"
"1","(3300,2625)","0","standard","I73";
;
CDS_LIB"standard"
BODY_TYPE"PLUMBING"
HDL_TAP"TRUE";
"B \NAC \NWC"2;
"S \NAC"
BN"21"55;
%"TAP"
"1","(3300,2575)","0","standard","I74";
;
CDS_LIB"standard"
BODY_TYPE"PLUMBING"
HDL_TAP"TRUE";
"B \NAC \NWC"2;
"S \NAC"
BN"20"56;
%"TAP"
"1","(3300,2525)","0","standard","I75";
;
CDS_LIB"standard"
BODY_TYPE"PLUMBING"
HDL_TAP"TRUE";
"B \NAC \NWC"2;
"S \NAC"
BN"19"57;
%"TAP"
"1","(3300,2925)","0","standard","I76";
;
CDS_LIB"standard"
BODY_TYPE"PLUMBING"
HDL_TAP"TRUE";
"B \NAC \NWC"1;
"S \NAC"
BN"2"98;
%"TAP"
"1","(3300,2975)","0","standard","I77";
;
CDS_LIB"standard"
BODY_TYPE"PLUMBING"
HDL_TAP"TRUE";
"B \NAC \NWC"1;
"S \NAC"
BN"3"97;
%"TAP"
"1","(3300,2875)","0","standard","I78";
;
CDS_LIB"standard"
BODY_TYPE"PLUMBING"
HDL_TAP"TRUE";
"B \NAC \NWC"1;
"S \NAC"
BN"1"99;
%"TAP"
"1","(3300,2825)","0","standard","I79";
;
CDS_LIB"standard"
BODY_TYPE"PLUMBING"
HDL_TAP"TRUE";
"B \NAC \NWC"1;
"S \NAC"
BN"0"100;
%"TAP"
"1","(-75,1825)","2","standard","I8";
;
CDS_LIB"standard"
BODY_TYPE"PLUMBING"
HDL_TAP"TRUE";
"B \NAC \NWC"4;
"S \NAC"
BN"5"23;
%"TAP"
"1","(3300,3025)","0","standard","I80";
;
CDS_LIB"standard"
BODY_TYPE"PLUMBING"
HDL_TAP"TRUE";
"B \NAC \NWC"1;
"S \NAC"
BN"4"96;
%"TAP"
"1","(3300,3075)","0","standard","I81";
;
CDS_LIB"standard"
BODY_TYPE"PLUMBING"
HDL_TAP"TRUE";
"B \NAC \NWC"1;
"S \NAC"
BN"5"95;
%"TAP"
"1","(3300,3225)","0","standard","I82";
;
CDS_LIB"standard"
BODY_TYPE"PLUMBING"
HDL_TAP"TRUE";
"B \NAC \NWC"1;
"S \NAC"
BN"8"92;
%"TAP"
"1","(3300,3125)","0","standard","I83";
;
CDS_LIB"standard"
BODY_TYPE"PLUMBING"
HDL_TAP"TRUE";
"B \NAC \NWC"1;
"S \NAC"
BN"6"94;
%"TAP"
"1","(3300,3175)","0","standard","I84";
;
CDS_LIB"standard"
BODY_TYPE"PLUMBING"
HDL_TAP"TRUE";
"B \NAC \NWC"1;
"S \NAC"
BN"7"93;
%"TAP"
"1","(3300,3325)","0","standard","I85";
;
CDS_LIB"standard"
BODY_TYPE"PLUMBING"
HDL_TAP"TRUE";
"B \NAC \NWC"1;
"S \NAC"
BN"10"90;
%"TAP"
"1","(3300,3275)","0","standard","I86";
;
CDS_LIB"standard"
BODY_TYPE"PLUMBING"
HDL_TAP"TRUE";
"B \NAC \NWC"1;
"S \NAC"
BN"9"91;
%"TAP"
"1","(3300,3375)","0","standard","I87";
;
CDS_LIB"standard"
BODY_TYPE"PLUMBING"
HDL_TAP"TRUE";
"B \NAC \NWC"1;
"S \NAC"
BN"11"89;
%"TAP"
"1","(3300,3475)","0","standard","I88";
;
CDS_LIB"standard"
BODY_TYPE"PLUMBING"
HDL_TAP"TRUE";
"B \NAC \NWC"1;
"S \NAC"
BN"13"87;
%"TAP"
"1","(3300,3425)","0","standard","I89";
;
CDS_LIB"standard"
BODY_TYPE"PLUMBING"
HDL_TAP"TRUE";
"B \NAC \NWC"1;
"S \NAC"
BN"12"88;
%"TAP"
"1","(-75,1925)","2","standard","I9";
;
CDS_LIB"standard"
BODY_TYPE"PLUMBING"
HDL_TAP"TRUE";
"B \NAC \NWC"4;
"S \NAC"
BN"7"21;
%"TAP"
"1","(3300,3575)","0","standard","I90";
;
CDS_LIB"standard"
BODY_TYPE"PLUMBING"
HDL_TAP"TRUE";
"B \NAC \NWC"1;
"S \NAC"
BN"15"85;
%"TAP"
"1","(3300,3525)","0","standard","I91";
;
CDS_LIB"standard"
BODY_TYPE"PLUMBING"
HDL_TAP"TRUE";
"B \NAC \NWC"1;
"S \NAC"
BN"14"86;
%"TAP"
"1","(3300,3625)","0","standard","I92";
;
CDS_LIB"standard"
BODY_TYPE"PLUMBING"
HDL_TAP"TRUE";
"B \NAC \NWC"1;
"S \NAC"
BN"16"84;
%"TAP"
"1","(3300,3725)","0","standard","I93";
;
CDS_LIB"standard"
BODY_TYPE"PLUMBING"
HDL_TAP"TRUE";
"B \NAC \NWC"1;
"S \NAC"
BN"18"82;
%"TAP"
"1","(3300,3675)","0","standard","I94";
;
CDS_LIB"standard"
BODY_TYPE"PLUMBING"
HDL_TAP"TRUE";
"B \NAC \NWC"1;
"S \NAC"
BN"17"83;
%"TAP"
"1","(3300,3775)","0","standard","I95";
;
CDS_LIB"standard"
BODY_TYPE"PLUMBING"
HDL_TAP"TRUE";
"B \NAC \NWC"1;
"S \NAC"
BN"19"81;
%"TAP"
"1","(3300,3825)","0","standard","I96";
;
CDS_LIB"standard"
BODY_TYPE"PLUMBING"
HDL_TAP"TRUE";
"B \NAC \NWC"1;
"S \NAC"
BN"20"80;
%"TAP"
"1","(3300,3875)","0","standard","I97";
;
CDS_LIB"standard"
BODY_TYPE"PLUMBING"
HDL_TAP"TRUE";
"B \NAC \NWC"1;
"S \NAC"
BN"21"79;
%"TAP"
"1","(3300,3925)","0","standard","I98";
;
CDS_LIB"standard"
BODY_TYPE"PLUMBING"
HDL_TAP"TRUE";
"B \NAC \NWC"1;
"S \NAC"
BN"22"78;
%"TAP"
"1","(3300,3975)","0","standard","I99";
;
CDS_LIB"standard"
BODY_TYPE"PLUMBING"
HDL_TAP"TRUE";
"B \NAC \NWC"1;
"S \NAC"
BN"23"77;
END.
